(kicad_pcb
	(version 20260206)
	(generator "pcbnew")
	(generator_version "10.0")
	(general
		(thickness 1.6)
		(legacy_teardrops no)
	)
	(paper "A4")
	(title_block
		(title "03242023_DA0F0TMBIJ0_F0T_Motherboard_J_brd_V01_OCP.brd")
		(comment 1 "Grand Teton / footprints 704-709 of 6105")
	)
	(layers
		(0 "F.Cu" signal "TOP")
		(4 "In1.Cu" signal "GND")
		(6 "In2.Cu" signal "IN1")
		(8 "In3.Cu" signal "GND1")
		(10 "In4.Cu" signal "IN2")
		(12 "In5.Cu" signal "GND2")
		(14 "In6.Cu" signal "IN3")
		(16 "In7.Cu" signal "GND3")
		(18 "In8.Cu" signal "VCC")
		(20 "In9.Cu" signal "VCC1")
		(22 "In10.Cu" signal "GND4")
		(24 "In11.Cu" signal "IN4")
		(26 "In12.Cu" signal "GND5")
		(28 "In13.Cu" signal "IN5")
		(30 "In14.Cu" signal "GND6")
		(32 "In15.Cu" signal "IN6")
		(34 "In16.Cu" signal "GND7")
		(2 "B.Cu" signal "BOTTOM")
		(9 "F.Adhes" user "F.Adhesive")
		(11 "B.Adhes" user "B.Adhesive")
		(13 "F.Paste" user "Package Geometry/Pastemask Top")
		(15 "B.Paste" user "Package Geometry/Pastemask Bottom")
		(5 "F.SilkS" user "Ref Des/Silkscreen Top")
		(7 "B.SilkS" user "Ref Des/Silkscreen Bottom")
		(1 "F.Mask" user "Board Geometry/Soldermask Top")
		(3 "B.Mask" user "Board Geometry/Soldermask Bottom")
		(17 "Dwgs.User" user "User.Drawings")
		(19 "Cmts.User" user "User.Comments")
		(21 "Eco1.User" user "User.Eco1")
		(23 "Eco2.User" user "User.Eco2")
		(25 "Edge.Cuts" user "Board Geometry/Outline")
		(27 "Margin" user)
		(31 "F.CrtYd" user "Package Geometry/Place Bound Top")
		(29 "B.CrtYd" user "Package Geometry/Place Bound Bottom")
		(35 "F.Fab" user "Ref Des/Assembly Top")
		(33 "B.Fab" user "Ref Des/Assembly Bottom")
	)
	(footprint ""
		(layer "F.Cu")
		(at 147.5359 -40.051736 180)
		(property "Reference" "R3303"
			(at 0 0 180)
			(layer "F.SilkS")
			(hide yes)
			(effects
				(font
					(size 1.27 1.27)
				)
			)
		)
		(property "Value" ""
			(at 0 0 180)
			(layer "F.Fab")
			(effects
				(font
					(size 1.27 1.27)
				)
			)
		)
		(duplicate_pad_numbers_are_jumpers no)
		(fp_line
			(start 0.7874 0.4064)
			(end -0.7874 0.4064)
			(stroke
				(width 0.1524)
				(type default)
			)
			(layer "F.SilkS")
		)
		(fp_line
			(start 0.7874 -0.4064)
			(end 0.7874 0.4064)
			(stroke
				(width 0.1524)
				(type default)
			)
			(layer "F.SilkS")
		)
		(fp_line
			(start -0.7874 0.4064)
			(end -0.7874 -0.4064)
			(stroke
				(width 0.1524)
				(type default)
			)
			(layer "F.SilkS")
		)
		(fp_line
			(start -0.7874 -0.4064)
			(end 0.7874 -0.4064)
			(stroke
				(width 0.1524)
				(type default)
			)
			(layer "F.SilkS")
		)
		(fp_line
			(start 0.67945 0.3048)
			(end 0.120396 0.3048)
			(stroke
				(width 0.1)
				(type default)
			)
			(layer "F.Fab")
		)
		(fp_line
			(start 0.67945 -0.3048)
			(end 0.67945 0.3048)
			(stroke
				(width 0.1)
				(type default)
			)
			(layer "F.Fab")
		)
		(fp_line
			(start 0.12065 -0.2794)
			(end 0.12065 -0.3048)
			(stroke
				(width 0.1)
				(type default)
			)
			(layer "F.Fab")
		)
		(fp_line
			(start 0.12065 -0.3048)
			(end 0.67945 -0.3048)
			(stroke
				(width 0.1)
				(type default)
			)
			(layer "F.Fab")
		)
		(fp_line
			(start 0.120396 0.3048)
			(end 0.120396 0.2794)
			(stroke
				(width 0.1)
				(type default)
			)
			(layer "F.Fab")
		)
		(fp_line
			(start 0.120396 0.2794)
			(end -0.12065 0.2794)
			(stroke
				(width 0.1)
				(type default)
			)
			(layer "F.Fab")
		)
		(fp_line
			(start -0.12065 0.3048)
			(end -0.67945 0.3048)
			(stroke
				(width 0.1)
				(type default)
			)
			(layer "F.Fab")
		)
		(fp_line
			(start -0.12065 0.2794)
			(end -0.12065 0.3048)
			(stroke
				(width 0.1)
				(type default)
			)
			(layer "F.Fab")
		)
		(fp_line
			(start -0.12065 -0.2794)
			(end 0.12065 -0.2794)
			(stroke
				(width 0.1)
				(type default)
			)
			(layer "F.Fab")
		)
		(fp_line
			(start -0.12065 -0.305054)
			(end -0.12065 -0.2794)
			(stroke
				(width 0.1)
				(type default)
			)
			(layer "F.Fab")
		)
		(fp_line
			(start -0.67945 0.3048)
			(end -0.67945 -0.305054)
			(stroke
				(width 0.1)
				(type default)
			)
			(layer "F.Fab")
		)
		(fp_line
			(start -0.67945 -0.305054)
			(end -0.12065 -0.305054)
			(stroke
				(width 0.1)
				(type default)
			)
			(layer "F.Fab")
		)
		(pad "1" smd circle
			(at -0.40005 0 180)
			(size 0 0)
			(layers "F.Cu" "F.Mask" "F.Paste")
			(net "OCP_SFF_PRSNT_ALL_R_N")
		)
		(pad "2" smd circle
			(at 0.40005 0 180)
			(size 0 0)
			(layers "F.Cu" "F.Mask" "F.Paste")
			(net "OCP_SFF_PRSNT_ALL_R1_N")
		)
	)
	(footprint ""
		(layer "F.Cu")
		(at 159.274256 -64.694308 90)
		(property "Reference" "C1592"
			(at 0 0 90)
			(layer "F.SilkS")
			(hide yes)
			(effects
				(font
					(size 1.27 1.27)
				)
			)
		)
		(property "Value" ""
			(at 0 0 90)
			(layer "F.Fab")
			(effects
				(font
					(size 1.27 1.27)
				)
			)
		)
		(duplicate_pad_numbers_are_jumpers no)
		(fp_line
			(start 0.7874 -0.4064)
			(end 0.7874 0.4064)
			(stroke
				(width 0.1524)
				(type default)
			)
			(layer "F.SilkS")
		)
		(fp_line
			(start -0.7874 -0.4064)
			(end 0.7874 -0.4064)
			(stroke
				(width 0.1524)
				(type default)
			)
			(layer "F.SilkS")
		)
		(fp_line
			(start 0.7874 0.4064)
			(end -0.7874 0.4064)
			(stroke
				(width 0.1524)
				(type default)
			)
			(layer "F.SilkS")
		)
		(fp_line
			(start -0.7874 0.4064)
			(end -0.7874 -0.4064)
			(stroke
				(width 0.1524)
				(type default)
			)
			(layer "F.SilkS")
		)
		(fp_line
			(start -0.12065 -0.305054)
			(end -0.12065 -0.2794)
			(stroke
				(width 0.1)
				(type default)
			)
			(layer "F.Fab")
		)
		(fp_line
			(start -0.67945 -0.305054)
			(end -0.12065 -0.305054)
			(stroke
				(width 0.1)
				(type default)
			)
			(layer "F.Fab")
		)
		(fp_line
			(start 0.67945 -0.3048)
			(end 0.67945 0.3048)
			(stroke
				(width 0.1)
				(type default)
			)
			(layer "F.Fab")
		)
		(fp_line
			(start 0.12065 -0.3048)
			(end 0.67945 -0.3048)
			(stroke
				(width 0.1)
				(type default)
			)
			(layer "F.Fab")
		)
		(fp_line
			(start 0.12065 -0.2794)
			(end 0.12065 -0.3048)
			(stroke
				(width 0.1)
				(type default)
			)
			(layer "F.Fab")
		)
		(fp_line
			(start -0.12065 -0.2794)
			(end 0.12065 -0.2794)
			(stroke
				(width 0.1)
				(type default)
			)
			(layer "F.Fab")
		)
		(fp_line
			(start 0.120396 0.2794)
			(end -0.12065 0.2794)
			(stroke
				(width 0.1)
				(type default)
			)
			(layer "F.Fab")
		)
		(fp_line
			(start -0.12065 0.2794)
			(end -0.12065 0.3048)
			(stroke
				(width 0.1)
				(type default)
			)
			(layer "F.Fab")
		)
		(fp_line
			(start 0.67945 0.3048)
			(end 0.120396 0.3048)
			(stroke
				(width 0.1)
				(type default)
			)
			(layer "F.Fab")
		)
		(fp_line
			(start 0.120396 0.3048)
			(end 0.120396 0.2794)
			(stroke
				(width 0.1)
				(type default)
			)
			(layer "F.Fab")
		)
		(fp_line
			(start -0.12065 0.3048)
			(end -0.67945 0.3048)
			(stroke
				(width 0.1)
				(type default)
			)
			(layer "F.Fab")
		)
		(fp_line
			(start -0.67945 0.3048)
			(end -0.67945 -0.305054)
			(stroke
				(width 0.1)
				(type default)
			)
			(layer "F.Fab")
		)
		(pad "1" smd circle
			(at -0.40005 0 90)
			(size 0 0)
			(layers "F.Cu" "F.Mask" "F.Paste")
			(net "P3V3_AUX")
		)
		(pad "2" smd circle
			(at 0.40005 0 90)
			(size 0 0)
			(layers "F.Cu" "F.Mask" "F.Paste")
			(net "GND")
		)
	)
	(footprint ""
		(layer "F.Cu")
		(at 271.225772 -71.4756)
		(property "Reference" "PL150"
			(at -4.800092 -4.062222 0)
			(unlocked yes)
			(layer "F.SilkS")
			(effects
				(font
					(size 0.7874 0.5842)
					(thickness 0.1524)
				)
				(justify left)
			)
		)
		(property "Value" ""
			(at 0 0 0)
			(layer "F.Fab")
			(effects
				(font
					(size 1.27 1.27)
				)
			)
		)
		(duplicate_pad_numbers_are_jumpers no)
		(fp_line
			(start -4.800092 -3.199892)
			(end 4.800092 -3.199892)
			(stroke
				(width 0.1524)
				(type default)
			)
			(layer "F.SilkS")
		)
		(fp_line
			(start -4.800092 -1.6891)
			(end -4.800092 -3.199892)
			(stroke
				(width 0.1524)
				(type default)
			)
			(layer "F.SilkS")
		)
		(fp_line
			(start -4.800092 3.199892)
			(end -4.800092 1.6891)
			(stroke
				(width 0.1524)
				(type default)
			)
			(layer "F.SilkS")
		)
		(fp_line
			(start 4.800092 -3.199892)
			(end 4.800092 -1.6891)
			(stroke
				(width 0.1524)
				(type default)
			)
			(layer "F.SilkS")
		)
		(fp_line
			(start 4.800092 1.6891)
			(end 4.800092 3.199892)
			(stroke
				(width 0.1524)
				(type default)
			)
			(layer "F.SilkS")
		)
		(fp_line
			(start 4.800092 3.199892)
			(end -4.800092 3.199892)
			(stroke
				(width 0.1524)
				(type default)
			)
			(layer "F.SilkS")
		)
		(fp_line
			(start -4.800092 -3.199892)
			(end 4.800092 -3.199892)
			(stroke
				(width 0.1)
				(type default)
			)
			(layer "F.Fab")
		)
		(fp_line
			(start -4.800092 3.199892)
			(end -4.800092 -3.199892)
			(stroke
				(width 0.1)
				(type default)
			)
			(layer "F.Fab")
		)
		(fp_line
			(start 4.800092 -3.199892)
			(end 4.800092 3.199892)
			(stroke
				(width 0.1)
				(type default)
			)
			(layer "F.Fab")
		)
		(fp_line
			(start 4.800092 3.199892)
			(end -4.800092 3.199892)
			(stroke
				(width 0.1)
				(type default)
			)
			(layer "F.Fab")
		)
		(pad "1" smd rect
			(at -3.350006 0 90)
			(size 3.0988 3.2004)
			(layers "F.Cu" "F.Mask" "F.Paste")
			(net "SW_P1V05_PCH_AUX_SW")
		)
		(pad "2" smd rect
			(at 3.350006 0 90)
			(size 3.0988 3.2004)
			(layers "F.Cu" "F.Mask" "F.Paste")
			(net "P1V05_PCH_AUX")
		)
	)
	(footprint ""
		(layer "F.Cu")
		(at 178.044602 -32.950912 90)
		(property "Reference" "PR3999"
			(at 0 0 90)
			(layer "F.SilkS")
			(hide yes)
			(effects
				(font
					(size 1.27 1.27)
				)
			)
		)
		(property "Value" ""
			(at 0 0 90)
			(layer "F.Fab")
			(effects
				(font
					(size 1.27 1.27)
				)
			)
		)
		(duplicate_pad_numbers_are_jumpers no)
		(fp_line
			(start 0.7874 -0.4064)
			(end 0.7874 0.4064)
			(stroke
				(width 0.1524)
				(type default)
			)
			(layer "F.SilkS")
		)
		(fp_line
			(start -0.7874 -0.4064)
			(end 0.7874 -0.4064)
			(stroke
				(width 0.1524)
				(type default)
			)
			(layer "F.SilkS")
		)
		(fp_line
			(start 0.7874 0.4064)
			(end -0.7874 0.4064)
			(stroke
				(width 0.1524)
				(type default)
			)
			(layer "F.SilkS")
		)
		(fp_line
			(start -0.7874 0.4064)
			(end -0.7874 -0.4064)
			(stroke
				(width 0.1524)
				(type default)
			)
			(layer "F.SilkS")
		)
		(fp_line
			(start -0.12065 -0.305054)
			(end -0.12065 -0.2794)
			(stroke
				(width 0.1)
				(type default)
			)
			(layer "F.Fab")
		)
		(fp_line
			(start -0.67945 -0.305054)
			(end -0.12065 -0.305054)
			(stroke
				(width 0.1)
				(type default)
			)
			(layer "F.Fab")
		)
		(fp_line
			(start 0.67945 -0.3048)
			(end 0.67945 0.3048)
			(stroke
				(width 0.1)
				(type default)
			)
			(layer "F.Fab")
		)
		(fp_line
			(start 0.12065 -0.3048)
			(end 0.67945 -0.3048)
			(stroke
				(width 0.1)
				(type default)
			)
			(layer "F.Fab")
		)
		(fp_line
			(start 0.12065 -0.2794)
			(end 0.12065 -0.3048)
			(stroke
				(width 0.1)
				(type default)
			)
			(layer "F.Fab")
		)
		(fp_line
			(start -0.12065 -0.2794)
			(end 0.12065 -0.2794)
			(stroke
				(width 0.1)
				(type default)
			)
			(layer "F.Fab")
		)
		(fp_line
			(start 0.120396 0.2794)
			(end -0.12065 0.2794)
			(stroke
				(width 0.1)
				(type default)
			)
			(layer "F.Fab")
		)
		(fp_line
			(start -0.12065 0.2794)
			(end -0.12065 0.3048)
			(stroke
				(width 0.1)
				(type default)
			)
			(layer "F.Fab")
		)
		(fp_line
			(start 0.67945 0.3048)
			(end 0.120396 0.3048)
			(stroke
				(width 0.1)
				(type default)
			)
			(layer "F.Fab")
		)
		(fp_line
			(start 0.120396 0.3048)
			(end 0.120396 0.2794)
			(stroke
				(width 0.1)
				(type default)
			)
			(layer "F.Fab")
		)
		(fp_line
			(start -0.12065 0.3048)
			(end -0.67945 0.3048)
			(stroke
				(width 0.1)
				(type default)
			)
			(layer "F.Fab")
		)
		(fp_line
			(start -0.67945 0.3048)
			(end -0.67945 -0.305054)
			(stroke
				(width 0.1)
				(type default)
			)
			(layer "F.Fab")
		)
		(pad "1" smd circle
			(at -0.40005 0 90)
			(size 0 0)
			(layers "F.Cu" "F.Mask" "F.Paste")
			(net "P12V_SCM_ISET")
		)
		(pad "2" smd circle
			(at 0.40005 0 90)
			(size 0 0)
			(layers "F.Cu" "F.Mask" "F.Paste")
			(net "GND")
		)
	)
	(footprint ""
		(layer "F.Cu")
		(at 181.135782 -426.8216 180)
		(property "Reference" "R2796"
			(at 0 0 180)
			(layer "F.SilkS")
			(hide yes)
			(effects
				(font
					(size 1.27 1.27)
				)
			)
		)
		(property "Value" ""
			(at 0 0 180)
			(layer "F.Fab")
			(effects
				(font
					(size 1.27 1.27)
				)
			)
		)
		(duplicate_pad_numbers_are_jumpers no)
		(fp_line
			(start 0.7874 0.4064)
			(end -0.7874 0.4064)
			(stroke
				(width 0.1524)
				(type default)
			)
			(layer "F.SilkS")
		)
		(fp_line
			(start 0.7874 -0.4064)
			(end 0.7874 0.4064)
			(stroke
				(width 0.1524)
				(type default)
			)
			(layer "F.SilkS")
		)
		(fp_line
			(start -0.7874 0.4064)
			(end -0.7874 -0.4064)
			(stroke
				(width 0.1524)
				(type default)
			)
			(layer "F.SilkS")
		)
		(fp_line
			(start -0.7874 -0.4064)
			(end 0.7874 -0.4064)
			(stroke
				(width 0.1524)
				(type default)
			)
			(layer "F.SilkS")
		)
		(fp_line
			(start 0.67945 0.3048)
			(end 0.120396 0.3048)
			(stroke
				(width 0.1)
				(type default)
			)
			(layer "F.Fab")
		)
		(fp_line
			(start 0.67945 -0.3048)
			(end 0.67945 0.3048)
			(stroke
				(width 0.1)
				(type default)
			)
			(layer "F.Fab")
		)
		(fp_line
			(start 0.12065 -0.2794)
			(end 0.12065 -0.3048)
			(stroke
				(width 0.1)
				(type default)
			)
			(layer "F.Fab")
		)
		(fp_line
			(start 0.12065 -0.3048)
			(end 0.67945 -0.3048)
			(stroke
				(width 0.1)
				(type default)
			)
			(layer "F.Fab")
		)
		(fp_line
			(start 0.120396 0.3048)
			(end 0.120396 0.2794)
			(stroke
				(width 0.1)
				(type default)
			)
			(layer "F.Fab")
		)
		(fp_line
			(start 0.120396 0.2794)
			(end -0.12065 0.2794)
			(stroke
				(width 0.1)
				(type default)
			)
			(layer "F.Fab")
		)
		(fp_line
			(start -0.12065 0.3048)
			(end -0.67945 0.3048)
			(stroke
				(width 0.1)
				(type default)
			)
			(layer "F.Fab")
		)
		(fp_line
			(start -0.12065 0.2794)
			(end -0.12065 0.3048)
			(stroke
				(width 0.1)
				(type default)
			)
			(layer "F.Fab")
		)
		(fp_line
			(start -0.12065 -0.2794)
			(end 0.12065 -0.2794)
			(stroke
				(width 0.1)
				(type default)
			)
			(layer "F.Fab")
		)
		(fp_line
			(start -0.12065 -0.305054)
			(end -0.12065 -0.2794)
			(stroke
				(width 0.1)
				(type default)
			)
			(layer "F.Fab")
		)
		(fp_line
			(start -0.67945 0.3048)
			(end -0.67945 -0.305054)
			(stroke
				(width 0.1)
				(type default)
			)
			(layer "F.Fab")
		)
		(fp_line
			(start -0.67945 -0.305054)
			(end -0.12065 -0.305054)
			(stroke
				(width 0.1)
				(type default)
			)
			(layer "F.Fab")
		)
		(pad "1" smd circle
			(at -0.40005 0 180)
			(size 0 0)
			(layers "F.Cu" "F.Mask" "F.Paste")
			(net "FM_PDB_BUF_EN_R")
		)
		(pad "2" smd circle
			(at 0.40005 0 180)
			(size 0 0)
			(layers "F.Cu" "F.Mask" "F.Paste")
			(net "FM_MB_PDB_SMB9_R_EN")
		)
	)
	(footprint ""
		(layer "F.Cu")
		(at 353.254818 -245.634002 -90)
		(property "Reference" "C983"
			(at 0 0 270)
			(layer "F.SilkS")
			(hide yes)
			(effects
				(font
					(size 1.27 1.27)
				)
			)
		)
		(property "Value" ""
			(at 0 0 270)
			(layer "F.Fab")
			(effects
				(font
					(size 1.27 1.27)
				)
			)
		)
		(duplicate_pad_numbers_are_jumpers no)
		(fp_line
			(start -0.7874 0.4064)
			(end -0.7874 -0.4064)
			(stroke
				(width 0.1524)
				(type default)
			)
			(layer "F.SilkS")
		)
		(fp_line
			(start 0.7874 0.4064)
			(end -0.7874 0.4064)
			(stroke
				(width 0.1524)
				(type default)
			)
			(layer "F.SilkS")
		)
		(fp_line
			(start -0.7874 -0.4064)
			(end 0.7874 -0.4064)
			(stroke
				(width 0.1524)
				(type default)
			)
			(layer "F.SilkS")
		)
		(fp_line
			(start 0.7874 -0.4064)
			(end 0.7874 0.4064)
			(stroke
				(width 0.1524)
				(type default)
			)
			(layer "F.SilkS")
		)
		(fp_line
			(start -0.67945 0.3048)
			(end -0.67945 -0.305054)
			(stroke
				(width 0.1)
				(type default)
			)
			(layer "F.Fab")
		)
		(fp_line
			(start -0.12065 0.3048)
			(end -0.67945 0.3048)
			(stroke
				(width 0.1)
				(type default)
			)
			(layer "F.Fab")
		)
		(fp_line
			(start 0.120396 0.3048)
			(end 0.120396 0.2794)
			(stroke
				(width 0.1)
				(type default)
			)
			(layer "F.Fab")
		)
		(fp_line
			(start 0.67945 0.3048)
			(end 0.120396 0.3048)
			(stroke
				(width 0.1)
				(type default)
			)
			(layer "F.Fab")
		)
		(fp_line
			(start -0.12065 0.2794)
			(end -0.12065 0.3048)
			(stroke
				(width 0.1)
				(type default)
			)
			(layer "F.Fab")
		)
		(fp_line
			(start 0.120396 0.2794)
			(end -0.12065 0.2794)
			(stroke
				(width 0.1)
				(type default)
			)
			(layer "F.Fab")
		)
		(fp_line
			(start -0.12065 -0.2794)
			(end 0.12065 -0.2794)
			(stroke
				(width 0.1)
				(type default)
			)
			(layer "F.Fab")
		)
		(fp_line
			(start 0.12065 -0.2794)
			(end 0.12065 -0.3048)
			(stroke
				(width 0.1)
				(type default)
			)
			(layer "F.Fab")
		)
		(fp_line
			(start 0.12065 -0.3048)
			(end 0.67945 -0.3048)
			(stroke
				(width 0.1)
				(type default)
			)
			(layer "F.Fab")
		)
		(fp_line
			(start 0.67945 -0.3048)
			(end 0.67945 0.3048)
			(stroke
				(width 0.1)
				(type default)
			)
			(layer "F.Fab")
		)
		(fp_line
			(start -0.67945 -0.305054)
			(end -0.12065 -0.305054)
			(stroke
				(width 0.1)
				(type default)
			)
			(layer "F.Fab")
		)
		(fp_line
			(start -0.12065 -0.305054)
			(end -0.12065 -0.2794)
			(stroke
				(width 0.1)
				(type default)
			)
			(layer "F.Fab")
		)
		(pad "1" smd circle
			(at -0.40005 0 270)
			(size 0 0)
			(layers "F.Cu" "F.Mask" "F.Paste")
			(net "PVCCIN_CPU0")
		)
		(pad "2" smd circle
			(at 0.40005 0 270)
			(size 0 0)
			(layers "F.Cu" "F.Mask" "F.Paste")
			(net "GND")
		)
	)
)
